(kicad_pcb
	(version 20260206)
	(generator "pcbnew")
	(generator_version "10.0")
	(general
		(thickness 1.6)
		(legacy_teardrops no)
	)
	(paper "A4")
	(title_block
		(title "01162023_DA0F0TEBIF0_F0T_Expander_BD_F_brd_V02_OCP.brd")
		(comment 1 "Grand Teton / footprints 3087-3093 of 9728")
	)
	(layers
		(0 "F.Cu" signal "TOP")
		(4 "In1.Cu" signal "GND")
		(6 "In2.Cu" signal "VCC")
		(8 "In3.Cu" signal "VCC1")
		(10 "In4.Cu" signal "GND1")
		(12 "In5.Cu" signal "IN1")
		(14 "In6.Cu" signal "GND2")
		(16 "In7.Cu" signal "IN2")
		(18 "In8.Cu" signal "GND3")
		(20 "In9.Cu" signal "IN3")
		(22 "In10.Cu" signal "GND4")
		(24 "In11.Cu" signal "IN4")
		(26 "In12.Cu" signal "GND5")
		(28 "In13.Cu" signal "IN5")
		(30 "In14.Cu" signal "GND6")
		(32 "In15.Cu" signal "IN6")
		(34 "In16.Cu" signal "GND7")
		(2 "B.Cu" signal "BOTTOM")
		(9 "F.Adhes" user "F.Adhesive")
		(11 "B.Adhes" user "B.Adhesive")
		(13 "F.Paste" user "Package Geometry/Pastemask Top")
		(15 "B.Paste" user "Package Geometry/Pastemask Bottom")
		(5 "F.SilkS" user "Ref Des/Silkscreen Top")
		(7 "B.SilkS" user "Ref Des/Silkscreen Bottom")
		(1 "F.Mask" user "Board Geometry/Soldermask Top")
		(3 "B.Mask" user "Board Geometry/Soldermask Bottom")
		(17 "Dwgs.User" user "User.Drawings")
		(19 "Cmts.User" user "User.Comments")
		(21 "Eco1.User" user "User.Eco1")
		(23 "Eco2.User" user "User.Eco2")
		(25 "Edge.Cuts" user "Board Geometry/Outline")
		(27 "Margin" user)
		(31 "F.CrtYd" user "Package Geometry/Place Bound Top")
		(29 "B.CrtYd" user "Package Geometry/Place Bound Bottom")
		(35 "F.Fab" user "Ref Des/Assembly Top")
		(33 "B.Fab" user "Ref Des/Assembly Bottom")
	)
	(footprint ""
		(layer "F.Cu")
		(at 447.147188 -415.621216 90)
		(property "Reference" "R5599"
			(at 0 0 90)
			(layer "F.SilkS")
			(hide yes)
			(effects
				(font
					(size 1.27 1.27)
				)
			)
		)
		(property "Value" ""
			(at 0 0 90)
			(layer "F.Fab")
			(effects
				(font
					(size 1.27 1.27)
				)
			)
		)
		(duplicate_pad_numbers_are_jumpers no)
		(fp_line
			(start 0.7874 -0.4064)
			(end 0.7874 0.4064)
			(stroke
				(width 0.1524)
				(type default)
			)
			(layer "F.SilkS")
		)
		(fp_line
			(start -0.7874 -0.4064)
			(end 0.7874 -0.4064)
			(stroke
				(width 0.1524)
				(type default)
			)
			(layer "F.SilkS")
		)
		(fp_line
			(start 0.7874 0.4064)
			(end -0.7874 0.4064)
			(stroke
				(width 0.1524)
				(type default)
			)
			(layer "F.SilkS")
		)
		(fp_line
			(start -0.7874 0.4064)
			(end -0.7874 -0.4064)
			(stroke
				(width 0.1524)
				(type default)
			)
			(layer "F.SilkS")
		)
		(fp_line
			(start -0.12065 -0.305054)
			(end -0.12065 -0.2794)
			(stroke
				(width 0.1)
				(type default)
			)
			(layer "F.Fab")
		)
		(fp_line
			(start -0.67945 -0.305054)
			(end -0.12065 -0.305054)
			(stroke
				(width 0.1)
				(type default)
			)
			(layer "F.Fab")
		)
		(fp_line
			(start 0.67945 -0.3048)
			(end 0.67945 0.3048)
			(stroke
				(width 0.1)
				(type default)
			)
			(layer "F.Fab")
		)
		(fp_line
			(start 0.12065 -0.3048)
			(end 0.67945 -0.3048)
			(stroke
				(width 0.1)
				(type default)
			)
			(layer "F.Fab")
		)
		(fp_line
			(start 0.12065 -0.2794)
			(end 0.12065 -0.3048)
			(stroke
				(width 0.1)
				(type default)
			)
			(layer "F.Fab")
		)
		(fp_line
			(start -0.12065 -0.2794)
			(end 0.12065 -0.2794)
			(stroke
				(width 0.1)
				(type default)
			)
			(layer "F.Fab")
		)
		(fp_line
			(start 0.120396 0.2794)
			(end -0.12065 0.2794)
			(stroke
				(width 0.1)
				(type default)
			)
			(layer "F.Fab")
		)
		(fp_line
			(start -0.12065 0.2794)
			(end -0.12065 0.3048)
			(stroke
				(width 0.1)
				(type default)
			)
			(layer "F.Fab")
		)
		(fp_line
			(start 0.67945 0.3048)
			(end 0.120396 0.3048)
			(stroke
				(width 0.1)
				(type default)
			)
			(layer "F.Fab")
		)
		(fp_line
			(start 0.120396 0.3048)
			(end 0.120396 0.2794)
			(stroke
				(width 0.1)
				(type default)
			)
			(layer "F.Fab")
		)
		(fp_line
			(start -0.12065 0.3048)
			(end -0.67945 0.3048)
			(stroke
				(width 0.1)
				(type default)
			)
			(layer "F.Fab")
		)
		(fp_line
			(start -0.67945 0.3048)
			(end -0.67945 -0.305054)
			(stroke
				(width 0.1)
				(type default)
			)
			(layer "F.Fab")
		)
		(pad "1" smd circle
			(at -0.40005 0 90)
			(size 0 0)
			(layers "F.Cu" "F.Mask" "F.Paste")
			(net "LM75_1_A0")
		)
		(pad "2" smd circle
			(at 0.40005 0 90)
			(size 0 0)
			(layers "F.Cu" "F.Mask" "F.Paste")
			(net "P3V3_AUX")
		)
	)
	(footprint ""
		(layer "F.Cu")
		(at 237.587028 -277.078694 90)
		(property "Reference" "R792"
			(at 0 0 90)
			(layer "F.SilkS")
			(hide yes)
			(effects
				(font
					(size 1.27 1.27)
				)
			)
		)
		(property "Value" ""
			(at 0 0 90)
			(layer "F.Fab")
			(effects
				(font
					(size 1.27 1.27)
				)
			)
		)
		(duplicate_pad_numbers_are_jumpers no)
		(fp_line
			(start 3.937508 -1.8796)
			(end -3.937508 -1.8796)
			(stroke
				(width 0.1524)
				(type default)
			)
			(layer "F.SilkS")
		)
		(fp_line
			(start -3.937508 -1.8796)
			(end -3.937508 1.8796)
			(stroke
				(width 0.1524)
				(type default)
			)
			(layer "F.SilkS")
		)
		(fp_line
			(start 3.937508 1.8796)
			(end 3.937508 -1.8796)
			(stroke
				(width 0.1524)
				(type default)
			)
			(layer "F.SilkS")
		)
		(fp_line
			(start -3.937508 1.8796)
			(end 3.937508 1.8796)
			(stroke
				(width 0.1524)
				(type default)
			)
			(layer "F.SilkS")
		)
		(fp_line
			(start 3.275076 -1.674876)
			(end -3.275076 -1.674876)
			(stroke
				(width 0.1)
				(type default)
			)
			(layer "F.Fab")
		)
		(fp_line
			(start -3.275076 -1.674876)
			(end -3.275076 1.674876)
			(stroke
				(width 0.1)
				(type default)
			)
			(layer "F.Fab")
		)
		(fp_line
			(start 3.275076 1.674876)
			(end 3.275076 -1.674876)
			(stroke
				(width 0.1)
				(type default)
			)
			(layer "F.Fab")
		)
		(fp_line
			(start -3.275076 1.674876)
			(end 3.275076 1.674876)
			(stroke
				(width 0.1)
				(type default)
			)
			(layer "F.Fab")
		)
		(pad "1" smd rect
			(at -2.350008 0 90)
			(size 2.921 3.5052)
			(layers "F.Cu" "F.Mask" "F.Paste")
			(net "P1V25_PEX2")
		)
		(pad "2" smd rect
			(at 2.350008 0 90)
			(size 2.921 3.5052)
			(layers "F.Cu" "F.Mask" "F.Paste")
			(net "P1V25_PEX2_R")
		)
	)
	(footprint ""
		(layer "F.Cu")
		(at 271.480534 -135.815324)
		(property "Reference" "C455"
			(at 0 0 0)
			(layer "F.SilkS")
			(hide yes)
			(effects
				(font
					(size 1.27 1.27)
				)
			)
		)
		(property "Value" ""
			(at 0 0 0)
			(layer "F.Fab")
			(effects
				(font
					(size 1.27 1.27)
				)
			)
		)
		(duplicate_pad_numbers_are_jumpers no)
		(fp_line
			(start -0.299974 -0.150114)
			(end 0.299974 -0.150114)
			(stroke
				(width 0.1)
				(type default)
			)
			(layer "F.Fab")
		)
		(fp_line
			(start -0.299974 0.150114)
			(end -0.299974 -0.150114)
			(stroke
				(width 0.1)
				(type default)
			)
			(layer "F.Fab")
		)
		(fp_line
			(start 0.299974 -0.150114)
			(end 0.299974 0.150114)
			(stroke
				(width 0.1)
				(type default)
			)
			(layer "F.Fab")
		)
		(fp_line
			(start 0.299974 0.150114)
			(end -0.299974 0.150114)
			(stroke
				(width 0.1)
				(type default)
			)
			(layer "F.Fab")
		)
		(pad "1" smd rect
			(at -0.2667 0)
			(size 0.3048 0.381)
			(layers "F.Cu" "F.Mask" "F.Paste")
			(net "P5E_PEX2_STN1_TX_DN<31>")
		)
		(pad "2" smd rect
			(at 0.2667 0)
			(size 0.3048 0.381)
			(layers "F.Cu" "F.Mask" "F.Paste")
			(net "P5E_PEX2_STN1_TX_C_DN<31>")
		)
	)
	(footprint ""
		(layer "F.Cu")
		(at 408.071828 -24.807418)
		(property "Reference" "R453"
			(at 0 0 0)
			(layer "F.SilkS")
			(hide yes)
			(effects
				(font
					(size 1.27 1.27)
				)
			)
		)
		(property "Value" ""
			(at 0 0 0)
			(layer "F.Fab")
			(effects
				(font
					(size 1.27 1.27)
				)
			)
		)
		(duplicate_pad_numbers_are_jumpers no)
		(fp_line
			(start -0.7874 -0.4064)
			(end 0.7874 -0.4064)
			(stroke
				(width 0.1524)
				(type default)
			)
			(layer "F.SilkS")
		)
		(fp_line
			(start -0.7874 0.4064)
			(end -0.7874 -0.4064)
			(stroke
				(width 0.1524)
				(type default)
			)
			(layer "F.SilkS")
		)
		(fp_line
			(start 0.7874 -0.4064)
			(end 0.7874 0.4064)
			(stroke
				(width 0.1524)
				(type default)
			)
			(layer "F.SilkS")
		)
		(fp_line
			(start 0.7874 0.4064)
			(end -0.7874 0.4064)
			(stroke
				(width 0.1524)
				(type default)
			)
			(layer "F.SilkS")
		)
		(fp_line
			(start -0.67945 -0.305054)
			(end -0.12065 -0.305054)
			(stroke
				(width 0.1)
				(type default)
			)
			(layer "F.Fab")
		)
		(fp_line
			(start -0.67945 0.3048)
			(end -0.67945 -0.305054)
			(stroke
				(width 0.1)
				(type default)
			)
			(layer "F.Fab")
		)
		(fp_line
			(start -0.12065 -0.305054)
			(end -0.12065 -0.2794)
			(stroke
				(width 0.1)
				(type default)
			)
			(layer "F.Fab")
		)
		(fp_line
			(start -0.12065 -0.2794)
			(end 0.12065 -0.2794)
			(stroke
				(width 0.1)
				(type default)
			)
			(layer "F.Fab")
		)
		(fp_line
			(start -0.12065 0.2794)
			(end -0.12065 0.3048)
			(stroke
				(width 0.1)
				(type default)
			)
			(layer "F.Fab")
		)
		(fp_line
			(start -0.12065 0.3048)
			(end -0.67945 0.3048)
			(stroke
				(width 0.1)
				(type default)
			)
			(layer "F.Fab")
		)
		(fp_line
			(start 0.120396 0.2794)
			(end -0.12065 0.2794)
			(stroke
				(width 0.1)
				(type default)
			)
			(layer "F.Fab")
		)
		(fp_line
			(start 0.120396 0.3048)
			(end 0.120396 0.2794)
			(stroke
				(width 0.1)
				(type default)
			)
			(layer "F.Fab")
		)
		(fp_line
			(start 0.12065 -0.3048)
			(end 0.67945 -0.3048)
			(stroke
				(width 0.1)
				(type default)
			)
			(layer "F.Fab")
		)
		(fp_line
			(start 0.12065 -0.2794)
			(end 0.12065 -0.3048)
			(stroke
				(width 0.1)
				(type default)
			)
			(layer "F.Fab")
		)
		(fp_line
			(start 0.67945 -0.3048)
			(end 0.67945 0.3048)
			(stroke
				(width 0.1)
				(type default)
			)
			(layer "F.Fab")
		)
		(fp_line
			(start 0.67945 0.3048)
			(end 0.120396 0.3048)
			(stroke
				(width 0.1)
				(type default)
			)
			(layer "F.Fab")
		)
		(pad "1" smd circle
			(at -0.40005 0)
			(size 0 0)
			(layers "F.Cu" "F.Mask" "F.Paste")
			(net "P3V3_SSD14")
		)
		(pad "2" smd circle
			(at 0.40005 0)
			(size 0 0)
			(layers "F.Cu" "F.Mask" "F.Paste")
			(net "PU_CLKREQ14")
		)
	)
	(footprint ""
		(layer "F.Cu")
		(at 86.94039 -141.404848 -90)
		(property "Reference" "R94"
			(at 0 0 270)
			(layer "F.SilkS")
			(hide yes)
			(effects
				(font
					(size 1.27 1.27)
				)
			)
		)
		(property "Value" ""
			(at 0 0 270)
			(layer "F.Fab")
			(effects
				(font
					(size 1.27 1.27)
				)
			)
		)
		(duplicate_pad_numbers_are_jumpers no)
		(fp_line
			(start -0.7874 0.4064)
			(end -0.7874 -0.4064)
			(stroke
				(width 0.1524)
				(type default)
			)
			(layer "F.SilkS")
		)
		(fp_line
			(start 0.7874 0.4064)
			(end -0.7874 0.4064)
			(stroke
				(width 0.1524)
				(type default)
			)
			(layer "F.SilkS")
		)
		(fp_line
			(start -0.7874 -0.4064)
			(end 0.7874 -0.4064)
			(stroke
				(width 0.1524)
				(type default)
			)
			(layer "F.SilkS")
		)
		(fp_line
			(start 0.7874 -0.4064)
			(end 0.7874 0.4064)
			(stroke
				(width 0.1524)
				(type default)
			)
			(layer "F.SilkS")
		)
		(fp_line
			(start -0.67945 0.3048)
			(end -0.67945 -0.305054)
			(stroke
				(width 0.1)
				(type default)
			)
			(layer "F.Fab")
		)
		(fp_line
			(start -0.12065 0.3048)
			(end -0.67945 0.3048)
			(stroke
				(width 0.1)
				(type default)
			)
			(layer "F.Fab")
		)
		(fp_line
			(start 0.120396 0.3048)
			(end 0.120396 0.2794)
			(stroke
				(width 0.1)
				(type default)
			)
			(layer "F.Fab")
		)
		(fp_line
			(start 0.67945 0.3048)
			(end 0.120396 0.3048)
			(stroke
				(width 0.1)
				(type default)
			)
			(layer "F.Fab")
		)
		(fp_line
			(start -0.12065 0.2794)
			(end -0.12065 0.3048)
			(stroke
				(width 0.1)
				(type default)
			)
			(layer "F.Fab")
		)
		(fp_line
			(start 0.120396 0.2794)
			(end -0.12065 0.2794)
			(stroke
				(width 0.1)
				(type default)
			)
			(layer "F.Fab")
		)
		(fp_line
			(start -0.12065 -0.2794)
			(end 0.12065 -0.2794)
			(stroke
				(width 0.1)
				(type default)
			)
			(layer "F.Fab")
		)
		(fp_line
			(start 0.12065 -0.2794)
			(end 0.12065 -0.3048)
			(stroke
				(width 0.1)
				(type default)
			)
			(layer "F.Fab")
		)
		(fp_line
			(start 0.12065 -0.3048)
			(end 0.67945 -0.3048)
			(stroke
				(width 0.1)
				(type default)
			)
			(layer "F.Fab")
		)
		(fp_line
			(start 0.67945 -0.3048)
			(end 0.67945 0.3048)
			(stroke
				(width 0.1)
				(type default)
			)
			(layer "F.Fab")
		)
		(fp_line
			(start -0.67945 -0.305054)
			(end -0.12065 -0.305054)
			(stroke
				(width 0.1)
				(type default)
			)
			(layer "F.Fab")
		)
		(fp_line
			(start -0.12065 -0.305054)
			(end -0.12065 -0.2794)
			(stroke
				(width 0.1)
				(type default)
			)
			(layer "F.Fab")
		)
		(pad "1" smd circle
			(at -0.40005 0 270)
			(size 0 0)
			(layers "F.Cu" "F.Mask" "F.Paste")
			(net "PRSNT_NIC1_R_N")
		)
		(pad "2" smd circle
			(at 0.40005 0 270)
			(size 0 0)
			(layers "F.Cu" "F.Mask" "F.Paste")
			(net "PRSNT_NIC1_N")
		)
	)
	(footprint ""
		(layer "F.Cu")
		(at 254.60833 -257.102102)
		(property "Reference" "Q15"
			(at -2.42062 0.870712 90)
			(unlocked yes)
			(layer "F.SilkS")
			(effects
				(font
					(size 0.7874 0.5842)
					(thickness 0.1524)
				)
			)
		)
		(property "Value" ""
			(at 0 0 0)
			(layer "F.Fab")
			(effects
				(font
					(size 1.27 1.27)
				)
			)
		)
		(duplicate_pad_numbers_are_jumpers no)
		(fp_line
			(start -1.376172 -1.199896)
			(end -0.508 -1.199896)
			(stroke
				(width 0.1524)
				(type default)
			)
			(layer "F.SilkS")
		)
		(fp_line
			(start -1.376172 1.199896)
			(end -1.376172 -1.199896)
			(stroke
				(width 0.1524)
				(type default)
			)
			(layer "F.SilkS")
		)
		(fp_line
			(start -0.508 -1.199896)
			(end 0 -0.762)
			(stroke
				(width 0.1524)
				(type default)
			)
			(layer "F.SilkS")
		)
		(fp_line
			(start 0 -0.762)
			(end 0.508 -1.199896)
			(stroke
				(width 0.1524)
				(type default)
			)
			(layer "F.SilkS")
		)
		(fp_line
			(start 0.508 -1.199896)
			(end 1.376172 -1.199896)
			(stroke
				(width 0.1524)
				(type default)
			)
			(layer "F.SilkS")
		)
		(fp_line
			(start 1.376172 -1.199896)
			(end 1.376172 1.199896)
			(stroke
				(width 0.1524)
				(type default)
			)
			(layer "F.SilkS")
		)
		(fp_line
			(start 1.376172 1.199896)
			(end -1.376172 1.199896)
			(stroke
				(width 0.1524)
				(type default)
			)
			(layer "F.SilkS")
		)
		(fp_poly
			(pts
				(xy -1.4605 -0.7493) (xy -2.2225 -1.1303) (xy -2.2225 -0.3683)
			)
			(stroke
				(width 0)
				(type default)
			)
			(fill yes)
			(layer "F.SilkS")
		)
		(fp_line
			(start -0.674878 -1.100074)
			(end 0.674878 -1.100074)
			(stroke
				(width 0.1)
				(type default)
			)
			(layer "F.Fab")
		)
		(fp_line
			(start -0.674878 1.100074)
			(end -0.674878 -1.100074)
			(stroke
				(width 0.1)
				(type default)
			)
			(layer "F.Fab")
		)
		(fp_line
			(start 0.674878 -1.100074)
			(end 0.674878 1.100074)
			(stroke
				(width 0.1)
				(type default)
			)
			(layer "F.Fab")
		)
		(fp_line
			(start 0.674878 1.100074)
			(end -0.674878 1.100074)
			(stroke
				(width 0.1)
				(type default)
			)
			(layer "F.Fab")
		)
		(fp_poly
			(pts
				(xy -1.4605 -0.7493) (xy -2.2225 -1.1303) (xy -2.2225 -0.3683)
			)
			(stroke
				(width 0)
				(type default)
			)
			(fill yes)
			(layer "F.Fab")
		)
		(pad "1" smd rect
			(at -0.899922 -0.750062 270)
			(size 0.6096 0.6096)
			(layers "F.Cu" "F.Mask" "F.Paste")
			(net "GND")
		)
		(pad "2" smd rect
			(at -0.899922 0 270)
			(size 0.4064 0.6096)
			(layers "F.Cu" "F.Mask" "F.Paste")
			(net "PEX2_SYS_ERR_R_N")
		)
		(pad "3" smd rect
			(at -0.899922 0.750062 270)
			(size 0.6096 0.6096)
			(layers "F.Cu" "F.Mask" "F.Paste")
			(net "PEX2_SYS_ERR_3V3_N")
		)
		(pad "4" smd rect
			(at 0.899922 0.750062 270)
			(size 0.6096 0.6096)
			(layers "F.Cu" "F.Mask" "F.Paste")
			(net "GND")
		)
		(pad "5" smd rect
			(at 0.899922 0 270)
			(size 0.4064 0.6096)
			(layers "F.Cu" "F.Mask" "F.Paste")
			(net "PEX2_SYS_ERR_N_G")
		)
		(pad "6" smd rect
			(at 0.899922 -0.750062 270)
			(size 0.6096 0.6096)
			(layers "F.Cu" "F.Mask" "F.Paste")
			(net "PEX2_SYS_ERR_N_G")
		)
	)
	(footprint ""
		(layer "F.Cu")
		(at 167.148256 -166.302944 90)
		(property "Reference" "R147"
			(at 0 0 90)
			(layer "F.SilkS")
			(hide yes)
			(effects
				(font
					(size 1.27 1.27)
				)
			)
		)
		(property "Value" ""
			(at 0 0 90)
			(layer "F.Fab")
			(effects
				(font
					(size 1.27 1.27)
				)
			)
		)
		(duplicate_pad_numbers_are_jumpers no)
		(fp_line
			(start 0.7874 -0.4064)
			(end 0.7874 0.4064)
			(stroke
				(width 0.1524)
				(type default)
			)
			(layer "F.SilkS")
		)
		(fp_line
			(start -0.7874 -0.4064)
			(end 0.7874 -0.4064)
			(stroke
				(width 0.1524)
				(type default)
			)
			(layer "F.SilkS")
		)
		(fp_line
			(start 0.7874 0.4064)
			(end -0.7874 0.4064)
			(stroke
				(width 0.1524)
				(type default)
			)
			(layer "F.SilkS")
		)
		(fp_line
			(start -0.7874 0.4064)
			(end -0.7874 -0.4064)
			(stroke
				(width 0.1524)
				(type default)
			)
			(layer "F.SilkS")
		)
		(fp_line
			(start -0.12065 -0.305054)
			(end -0.12065 -0.2794)
			(stroke
				(width 0.1)
				(type default)
			)
			(layer "F.Fab")
		)
		(fp_line
			(start -0.67945 -0.305054)
			(end -0.12065 -0.305054)
			(stroke
				(width 0.1)
				(type default)
			)
			(layer "F.Fab")
		)
		(fp_line
			(start 0.67945 -0.3048)
			(end 0.67945 0.3048)
			(stroke
				(width 0.1)
				(type default)
			)
			(layer "F.Fab")
		)
		(fp_line
			(start 0.12065 -0.3048)
			(end 0.67945 -0.3048)
			(stroke
				(width 0.1)
				(type default)
			)
			(layer "F.Fab")
		)
		(fp_line
			(start 0.12065 -0.2794)
			(end 0.12065 -0.3048)
			(stroke
				(width 0.1)
				(type default)
			)
			(layer "F.Fab")
		)
		(fp_line
			(start -0.12065 -0.2794)
			(end 0.12065 -0.2794)
			(stroke
				(width 0.1)
				(type default)
			)
			(layer "F.Fab")
		)
		(fp_line
			(start 0.120396 0.2794)
			(end -0.12065 0.2794)
			(stroke
				(width 0.1)
				(type default)
			)
			(layer "F.Fab")
		)
		(fp_line
			(start -0.12065 0.2794)
			(end -0.12065 0.3048)
			(stroke
				(width 0.1)
				(type default)
			)
			(layer "F.Fab")
		)
		(fp_line
			(start 0.67945 0.3048)
			(end 0.120396 0.3048)
			(stroke
				(width 0.1)
				(type default)
			)
			(layer "F.Fab")
		)
		(fp_line
			(start 0.120396 0.3048)
			(end 0.120396 0.2794)
			(stroke
				(width 0.1)
				(type default)
			)
			(layer "F.Fab")
		)
		(fp_line
			(start -0.12065 0.3048)
			(end -0.67945 0.3048)
			(stroke
				(width 0.1)
				(type default)
			)
			(layer "F.Fab")
		)
		(fp_line
			(start -0.67945 0.3048)
			(end -0.67945 -0.305054)
			(stroke
				(width 0.1)
				(type default)
			)
			(layer "F.Fab")
		)
		(pad "1" smd circle
			(at -0.40005 0 90)
			(size 0 0)
			(layers "F.Cu" "F.Mask" "F.Paste")
			(net "RST_NIC2_PERST0_R_N")
		)
		(pad "2" smd circle
			(at 0.40005 0 90)
			(size 0 0)
			(layers "F.Cu" "F.Mask" "F.Paste")
			(net "RST_HP_NIC2_BUF_N")
		)
	)
)
